(kicad_pcb
	(version 20211014)
	(generator pcbnew)
	(general
    (thickness 1.6)
  )
	(paper "A4")
	(title_block
    (title "SA800U (Snapdragon 845) Baseboard")
    (date "2023-10-19")
    (rev "1.0.3")
    (company "Antmicro Ltd.")
    (comment 1 "www.antmicro.com")
		(comment 9 "footprints 193-202 of 589")
	)
	(layers
    (0 "F.Cu" signal)
    (1 "In1.Cu" power)
    (2 "In2.Cu" signal)
    (3 "In3.Cu" signal)
    (4 "In4.Cu" power)
    (31 "B.Cu" signal)
    (32 "B.Adhes" user "B.Adhesive")
    (33 "F.Adhes" user "F.Adhesive")
    (34 "B.Paste" user)
    (35 "F.Paste" user)
    (36 "B.SilkS" user "B.Silkscreen")
    (37 "F.SilkS" user "F.Silkscreen")
    (38 "B.Mask" user)
    (39 "F.Mask" user)
    (40 "Dwgs.User" user "User.Drawings")
    (41 "Cmts.User" user "User.Comments")
    (42 "Eco1.User" user "User.Eco1")
    (43 "Eco2.User" user "User.Eco2")
    (44 "Edge.Cuts" user)
    (45 "Margin" user)
    (46 "B.CrtYd" user "B.Courtyard")
    (47 "F.CrtYd" user "F.Courtyard")
    (48 "B.Fab" user)
    (49 "F.Fab" user)
  )
	(footprint "sa800u-baseboard-hw-footprints:R_0402_1005Metric" (layer "F.Cu")
    (tedit 5FD9C158)
    (at 142.55 136.9 -90)
    (descr "Resistor SMD 0402")
    (tags "resistor SMD 0402")
    (property "Author" "Antmicro")
    (property "License" "Apache-2.0")
    (property "MPN" "CR0402-FX-5100GLF")
    (property "Manufacturer" "Bourns")
    (property "Sheetfile" "hdmi-converter.kicad_sch")
    (property "Sheetname" "HDMI converter")
    (property "Tolerance" "1%")
    (property "Val" "510R")
    (attr smd)
    (fp_text reference "R53" (at -4.58 15.99 -90) (layer "F.SilkS")
      (effects (font (size 0.7 0.7) (thickness 0.15)) (justify left bottom))
    )
    (fp_text value "R_510R_0402" (at 0 1.4 -90) (layer "F.Fab")
      (effects (font (size 0.7 0.7) (thickness 0.15)) (justify left bottom))
    )
    (fp_text user "${REFERENCE}" (at -0.95 3.168 -90) (layer "F.Fab") hide
      (effects (font (size 0.7 0.7) (thickness 0.15)) (justify left bottom))
    )
    (fp_text user "License: Apache-2.0" (at -0.95 5.169 -90) (layer "F.Fab") hide
      (effects (font (size 0.7 0.7) (thickness 0.15)) (justify left bottom))
    )
    (fp_text user "Author: Antmicro" (at -0.95 4.169 -90) (layer "F.Fab") hide
      (effects (font (size 0.7 0.7) (thickness 0.15)) (justify left bottom))
    )
    (fp_rect (start -0.93 -0.47) (end 0.93 0.47) (layer "F.CrtYd") (width 0.05) (fill none))
    (fp_rect (start -0.5 -0.25) (end 0.5 0.25) (layer "F.Fab") (width 0.15) (fill none))
    (pad "1" smd roundrect (at -0.485 0 270) (size 0.59 0.64) (layers "F.Cu" "F.Paste" "F.Mask") (roundrect_rratio 0.25)
      (net 200 "/HDMI converter/HDMI_TX1_N") (pintype "passive"))
    (pad "2" smd roundrect (at 0.485 0 270) (size 0.59 0.64) (layers "F.Cu" "F.Paste" "F.Mask") (roundrect_rratio 0.25)
      (net 209 "/HDMI converter/VCOM") (pintype "passive"))
  )
	(footprint "sa800u-baseboard-hw-footprints:C_0402_1005Metric" (layer "F.Cu")
    (tedit 616D63CF)
    (at 148.815 123.7)
    (descr "Capacitor SMD 0402")
    (tags "capacitor SMD 0402")
    (property "Author" "Antmicro")
    (property "Dielectric" "X5R")
    (property "License" "Apache-2.0")
    (property "MPN" "GRM155R61H104KE14D")
    (property "Manufacturer" "Murata")
    (property "Sheetfile" "hdmi-converter.kicad_sch")
    (property "Sheetname" "HDMI converter")
    (property "Val" "100n")
    (property "Voltage" "50V")
    (attr smd)
    (fp_text reference "C30" (at -1.035 -0.59) (layer "F.SilkS")
      (effects (font (size 0.7 0.7) (thickness 0.15)) (justify left bottom))
    )
    (fp_text value "C_100n_0402" (at 0 1.4) (layer "F.Fab")
      (effects (font (size 0.7 0.7) (thickness 0.15)) (justify left bottom))
    )
    (fp_text user "Author: Antmicro" (at -0.932 4.17) (layer "F.Fab") hide
      (effects (font (size 0.7 0.7) (thickness 0.15)) (justify left bottom))
    )
    (fp_text user "${REFERENCE}" (at -0.932 3.168) (layer "F.Fab") hide
      (effects (font (size 0.7 0.7) (thickness 0.15)) (justify left bottom))
    )
    (fp_text user "License: Apache-2.0" (at -0.932 5.17) (layer "F.Fab") hide
      (effects (font (size 0.7 0.7) (thickness 0.15)) (justify left bottom))
    )
    (fp_rect (start -0.94 -0.47) (end 0.94 0.47) (layer "F.CrtYd") (width 0.05) (fill none))
    (fp_rect (start -0.499 -0.249) (end 0.499 0.249) (layer "F.Fab") (width 0.15) (fill none))
    (pad "1" smd roundrect (at -0.484 0) (size 0.59 0.64) (layers "F.Cu" "F.Paste" "F.Mask") (roundrect_rratio 0.25)
      (net 189 "/HDMI converter/LT9611_VCC12_RX") (pintype "passive"))
    (pad "2" smd roundrect (at 0.484 0) (size 0.59 0.64) (layers "F.Cu" "F.Paste" "F.Mask") (roundrect_rratio 0.25)
      (net 1 "GND") (pintype "passive"))
  )
	(footprint "sa800u-baseboard-hw-footprints:C_0402_1005Metric" (layer "F.Cu")
    (tedit 616D63CF)
    (at 143.15 134.95 -90)
    (descr "Capacitor SMD 0402")
    (tags "capacitor SMD 0402")
    (property "Author" "Antmicro")
    (property "Dielectric" "X5R")
    (property "License" "Apache-2.0")
    (property "MPN" "GRM155R61H104KE14D")
    (property "Manufacturer" "Murata")
    (property "Sheetfile" "hdmi-converter.kicad_sch")
    (property "Sheetname" "HDMI converter")
    (property "Val" "100n")
    (property "Voltage" "50V")
    (attr smd)
    (fp_text reference "C47" (at -4.579 15.99 -90) (layer "F.SilkS")
      (effects (font (size 0.7 0.7) (thickness 0.15)) (justify left bottom))
    )
    (fp_text value "C_100n_0402" (at 0 1.4 -90) (layer "F.Fab")
      (effects (font (size 0.7 0.7) (thickness 0.15)) (justify left bottom))
    )
    (fp_text user "License: Apache-2.0" (at -0.932 5.17 -90) (layer "F.Fab") hide
      (effects (font (size 0.7 0.7) (thickness 0.15)) (justify left bottom))
    )
    (fp_text user "${REFERENCE}" (at -0.932 3.168 -90) (layer "F.Fab") hide
      (effects (font (size 0.7 0.7) (thickness 0.15)) (justify left bottom))
    )
    (fp_text user "Author: Antmicro" (at -0.932 4.17 -90) (layer "F.Fab") hide
      (effects (font (size 0.7 0.7) (thickness 0.15)) (justify left bottom))
    )
    (fp_rect (start -0.94 -0.47) (end 0.94 0.47) (layer "F.CrtYd") (width 0.05) (fill none))
    (fp_rect (start -0.499 -0.249) (end 0.499 0.249) (layer "F.Fab") (width 0.15) (fill none))
    (pad "1" smd roundrect (at -0.484 0 270) (size 0.59 0.64) (layers "F.Cu" "F.Paste" "F.Mask") (roundrect_rratio 0.25)
      (net 199 "/HDMI converter/HDMI_TX_D1_N") (pintype "passive"))
    (pad "2" smd roundrect (at 0.484 0 270) (size 0.59 0.64) (layers "F.Cu" "F.Paste" "F.Mask") (roundrect_rratio 0.25)
      (net 200 "/HDMI converter/HDMI_TX1_N") (pintype "passive"))
  )
	(footprint "sa800u-baseboard-hw-footprints:R_0402_1005Metric" (layer "F.Cu")
    (tedit 5FD9C158)
    (at 144.75 136.9 -90)
    (descr "Resistor SMD 0402")
    (tags "resistor SMD 0402")
    (property "Author" "Antmicro")
    (property "License" "Apache-2.0")
    (property "MPN" "CR0402-FX-5100GLF")
    (property "Manufacturer" "Bourns")
    (property "Sheetfile" "hdmi-converter.kicad_sch")
    (property "Sheetname" "HDMI converter")
    (property "Tolerance" "1%")
    (property "Val" "510R")
    (attr smd)
    (fp_text reference "R54" (at -4.61 16.37 -90) (layer "F.SilkS")
      (effects (font (size 0.7 0.7) (thickness 0.15)) (justify left bottom))
    )
    (fp_text value "R_510R_0402" (at 0 1.4 -90) (layer "F.Fab")
      (effects (font (size 0.7 0.7) (thickness 0.15)) (justify left bottom))
    )
    (fp_text user "License: Apache-2.0" (at -0.95 5.169 -90) (layer "F.Fab") hide
      (effects (font (size 0.7 0.7) (thickness 0.15)) (justify left bottom))
    )
    (fp_text user "Author: Antmicro" (at -0.95 4.169 -90) (layer "F.Fab") hide
      (effects (font (size 0.7 0.7) (thickness 0.15)) (justify left bottom))
    )
    (fp_text user "${REFERENCE}" (at -0.95 3.168 -90) (layer "F.Fab") hide
      (effects (font (size 0.7 0.7) (thickness 0.15)) (justify left bottom))
    )
    (fp_rect (start -0.93 -0.47) (end 0.93 0.47) (layer "F.CrtYd") (width 0.05) (fill none))
    (fp_rect (start -0.5 -0.25) (end 0.5 0.25) (layer "F.Fab") (width 0.15) (fill none))
    (pad "1" smd roundrect (at -0.485 0 270) (size 0.59 0.64) (layers "F.Cu" "F.Paste" "F.Mask") (roundrect_rratio 0.25)
      (net 198 "/HDMI converter/HDMI_TX1_P") (pintype "passive"))
    (pad "2" smd roundrect (at 0.485 0 270) (size 0.59 0.64) (layers "F.Cu" "F.Paste" "F.Mask") (roundrect_rratio 0.25)
      (net 209 "/HDMI converter/VCOM") (pintype "passive"))
  )
	(footprint "sa800u-baseboard-hw-footprints:R_0402_1005Metric" (layer "F.Cu")
    (tedit 5FD9C158)
    (at 136.15 136.9 -90)
    (descr "Resistor SMD 0402")
    (tags "resistor SMD 0402")
    (property "Author" "Antmicro")
    (property "License" "Apache-2.0")
    (property "MPN" "CR0402-FX-5100GLF")
    (property "Manufacturer" "Bourns")
    (property "Sheetfile" "hdmi-converter.kicad_sch")
    (property "Sheetname" "HDMI converter")
    (property "Tolerance" "1%")
    (property "Val" "510R")
    (attr smd)
    (fp_text reference "R48" (at -4.64 15.39 -90) (layer "F.SilkS")
      (effects (font (size 0.7 0.7) (thickness 0.15)) (justify left bottom))
    )
    (fp_text value "R_510R_0402" (at 0 1.4 -90) (layer "F.Fab")
      (effects (font (size 0.7 0.7) (thickness 0.15)) (justify left bottom))
    )
    (fp_text user "License: Apache-2.0" (at -0.95 5.169 -90) (layer "F.Fab") hide
      (effects (font (size 0.7 0.7) (thickness 0.15)) (justify left bottom))
    )
    (fp_text user "Author: Antmicro" (at -0.95 4.169 -90) (layer "F.Fab") hide
      (effects (font (size 0.7 0.7) (thickness 0.15)) (justify left bottom))
    )
    (fp_text user "${REFERENCE}" (at -0.95 3.168 -90) (layer "F.Fab") hide
      (effects (font (size 0.7 0.7) (thickness 0.15)) (justify left bottom))
    )
    (fp_rect (start -0.93 -0.47) (end 0.93 0.47) (layer "F.CrtYd") (width 0.05) (fill none))
    (fp_rect (start -0.5 -0.25) (end 0.5 0.25) (layer "F.Fab") (width 0.15) (fill none))
    (pad "1" smd roundrect (at -0.485 0 270) (size 0.59 0.64) (layers "F.Cu" "F.Paste" "F.Mask") (roundrect_rratio 0.25)
      (net 208 "/HDMI converter/HDMI_CLK_N") (pintype "passive"))
    (pad "2" smd roundrect (at 0.485 0 270) (size 0.59 0.64) (layers "F.Cu" "F.Paste" "F.Mask") (roundrect_rratio 0.25)
      (net 209 "/HDMI converter/VCOM") (pintype "passive"))
  )
	(footprint "sa800u-baseboard-hw-footprints:C_0402_1005Metric" (layer "F.Cu")
    (tedit 616D63CF)
    (at 139.95 134.95 -90)
    (descr "Capacitor SMD 0402")
    (tags "capacitor SMD 0402")
    (property "Author" "Antmicro")
    (property "Dielectric" "X5R")
    (property "License" "Apache-2.0")
    (property "MPN" "GRM155R61H104KE14D")
    (property "Manufacturer" "Murata")
    (property "Sheetfile" "hdmi-converter.kicad_sch")
    (property "Sheetname" "HDMI converter")
    (property "Val" "100n")
    (property "Voltage" "50V")
    (attr smd)
    (fp_text reference "C48" (at -4.63 15.86 -90) (layer "F.SilkS")
      (effects (font (size 0.7 0.7) (thickness 0.15)) (justify left bottom))
    )
    (fp_text value "C_100n_0402" (at 0 1.4 -90) (layer "F.Fab")
      (effects (font (size 0.7 0.7) (thickness 0.15)) (justify left bottom))
    )
    (fp_text user "${REFERENCE}" (at -0.932 3.168 -90) (layer "F.Fab") hide
      (effects (font (size 0.7 0.7) (thickness 0.15)) (justify left bottom))
    )
    (fp_text user "License: Apache-2.0" (at -0.932 5.17 -90) (layer "F.Fab") hide
      (effects (font (size 0.7 0.7) (thickness 0.15)) (justify left bottom))
    )
    (fp_text user "Author: Antmicro" (at -0.932 4.17 -90) (layer "F.Fab") hide
      (effects (font (size 0.7 0.7) (thickness 0.15)) (justify left bottom))
    )
    (fp_rect (start -0.94 -0.47) (end 0.94 0.47) (layer "F.CrtYd") (width 0.05) (fill none))
    (fp_rect (start -0.499 -0.249) (end 0.499 0.249) (layer "F.Fab") (width 0.15) (fill none))
    (pad "1" smd roundrect (at -0.484 0 270) (size 0.59 0.64) (layers "F.Cu" "F.Paste" "F.Mask") (roundrect_rratio 0.25)
      (net 204 "/HDMI converter/HDMI_TX_D0_N") (pintype "passive"))
    (pad "2" smd roundrect (at 0.484 0 270) (size 0.59 0.64) (layers "F.Cu" "F.Paste" "F.Mask") (roundrect_rratio 0.25)
      (net 203 "/HDMI converter/HDMI_TX0_N") (pintype "passive"))
  )
	(footprint "sa800u-baseboard-hw-footprints:C_0402_1005Metric" (layer "F.Cu")
    (tedit 616D63CF)
    (at 148.2 130.9 180)
    (descr "Capacitor SMD 0402")
    (tags "capacitor SMD 0402")
    (property "Author" "Antmicro")
    (property "Dielectric" "")
    (property "License" "Apache-2.0")
    (property "MPN" "MC0402N150J500CT")
    (property "Manufacturer" "Multicomp")
    (property "Sheetfile" "hdmi-converter.kicad_sch")
    (property "Sheetname" "HDMI converter")
    (property "Val" "15p")
    (property "Voltage" "")
    (attr smd)
    (fp_text reference "C21" (at -0.89 -0.39 180) (layer "F.SilkS")
      (effects (font (size 0.7 0.7) (thickness 0.15)) (justify left bottom))
    )
    (fp_text value "C_15p_0402" (at 0 1.4 180) (layer "F.Fab")
      (effects (font (size 0.7 0.7) (thickness 0.15)) (justify left bottom))
    )
    (fp_text user "License: Apache-2.0" (at -0.932 5.17 180) (layer "F.Fab") hide
      (effects (font (size 0.7 0.7) (thickness 0.15)) (justify left bottom))
    )
    (fp_text user "Author: Antmicro" (at -0.932 4.17 180) (layer "F.Fab") hide
      (effects (font (size 0.7 0.7) (thickness 0.15)) (justify left bottom))
    )
    (fp_text user "${REFERENCE}" (at -0.932 3.168 180) (layer "F.Fab") hide
      (effects (font (size 0.7 0.7) (thickness 0.15)) (justify left bottom))
    )
    (fp_rect (start -0.94 -0.47) (end 0.94 0.47) (layer "F.CrtYd") (width 0.05) (fill none))
    (fp_rect (start -0.499 -0.249) (end 0.499 0.249) (layer "F.Fab") (width 0.15) (fill none))
    (pad "1" smd roundrect (at -0.484 0 180) (size 0.59 0.64) (layers "F.Cu" "F.Paste" "F.Mask") (roundrect_rratio 0.25)
      (net 192 "/HDMI converter/XTALI") (pintype "passive"))
    (pad "2" smd roundrect (at 0.484 0 180) (size 0.59 0.64) (layers "F.Cu" "F.Paste" "F.Mask") (roundrect_rratio 0.25)
      (net 1 "GND") (pintype "passive"))
  )
	(footprint "sa800u-baseboard-hw-footprints:C_0402_1005Metric" (layer "F.Cu")
    (tedit 616D63CF)
    (at 144.15 134.95 -90)
    (descr "Capacitor SMD 0402")
    (tags "capacitor SMD 0402")
    (property "Author" "Antmicro")
    (property "Dielectric" "X5R")
    (property "License" "Apache-2.0")
    (property "MPN" "GRM155R61H104KE14D")
    (property "Manufacturer" "Murata")
    (property "Sheetfile" "hdmi-converter.kicad_sch")
    (property "Sheetname" "HDMI converter")
    (property "Val" "100n")
    (property "Voltage" "50V")
    (attr smd)
    (fp_text reference "C51" (at -4.579 16.09 -90) (layer "F.SilkS")
      (effects (font (size 0.7 0.7) (thickness 0.15)) (justify left bottom))
    )
    (fp_text value "C_100n_0402" (at 0 1.4 -90) (layer "F.Fab")
      (effects (font (size 0.7 0.7) (thickness 0.15)) (justify left bottom))
    )
    (fp_text user "License: Apache-2.0" (at -0.932 5.17 -90) (layer "F.Fab") hide
      (effects (font (size 0.7 0.7) (thickness 0.15)) (justify left bottom))
    )
    (fp_text user "Author: Antmicro" (at -0.932 4.17 -90) (layer "F.Fab") hide
      (effects (font (size 0.7 0.7) (thickness 0.15)) (justify left bottom))
    )
    (fp_text user "${REFERENCE}" (at -0.932 3.168 -90) (layer "F.Fab") hide
      (effects (font (size 0.7 0.7) (thickness 0.15)) (justify left bottom))
    )
    (fp_rect (start -0.94 -0.47) (end 0.94 0.47) (layer "F.CrtYd") (width 0.05) (fill none))
    (fp_rect (start -0.499 -0.249) (end 0.499 0.249) (layer "F.Fab") (width 0.15) (fill none))
    (pad "1" smd roundrect (at -0.484 0 270) (size 0.59 0.64) (layers "F.Cu" "F.Paste" "F.Mask") (roundrect_rratio 0.25)
      (net 197 "/HDMI converter/HDMI_TX_D1_P") (pintype "passive"))
    (pad "2" smd roundrect (at 0.484 0 270) (size 0.59 0.64) (layers "F.Cu" "F.Paste" "F.Mask") (roundrect_rratio 0.25)
      (net 198 "/HDMI converter/HDMI_TX1_P") (pintype "passive"))
  )
	(footprint "sa800u-baseboard-hw-footprints:L_0603_1608Metric" (layer "F.Cu")
    (tedit 5D5D3F54)
    (at 133.1 131.375)
    (property "Author" "Antmicro")
    (property "IMax" "")
    (property "ISat" "")
    (property "License" "Apache-2.0")
    (property "MPN" "BRC1608TR35M")
    (property "Manufacturer" "Taiyo Yuden")
    (property "Sheetfile" "hdmi-converter.kicad_sch")
    (property "Sheetname" "HDMI converter")
    (property "Size" "")
    (property "Val" "350n/1.4A")
    (attr smd)
    (fp_text reference "L1" (at 0.92 0.395) (layer "F.SilkS")
      (effects (font (size 0.7 0.7) (thickness 0.15)) (justify left bottom))
    )
    (fp_text value "L_350n_1.4A_0603" (at 0 2) (layer "F.Fab")
      (effects (font (size 0.7 0.7) (thickness 0.15)) (justify left bottom))
    )
    (fp_text user "Author: Antmicro" (at -1.9 4.4) (layer "F.Fab") hide
      (effects (font (size 0.7 0.7) (thickness 0.15)) (justify left bottom))
    )
    (fp_text user "License: Apache-2.0" (at -1.9 5.75) (layer "F.Fab") hide
      (effects (font (size 0.7 0.7) (thickness 0.15)) (justify left bottom))
    )
    (fp_text user "${REFERENCE}" (at -1.9 3.1) (layer "F.Fab") hide
      (effects (font (size 0.7 0.7) (thickness 0.15)) (justify left bottom))
    )
    (fp_line (start -0.25 -0.45) (end 0.25 -0.45) (layer "F.SilkS") (width 0.1))
    (fp_line (start -0.25 0.45) (end 0.25 0.45) (layer "F.SilkS") (width 0.1))
    (fp_rect (start -1.15 -0.75) (end 1.15 0.75) (layer "F.CrtYd") (width 0.05) (fill none))
    (fp_rect (start -0.8 -0.4) (end 0.8 0.4) (layer "F.Fab") (width 0.1) (fill none))
    (pad "1" smd roundrect (at -0.625 0) (size 0.55 1) (layers "F.Cu" "F.Paste" "F.Mask") (roundrect_rratio 0.15)
      (net 131 "3V3_SYS") (pintype "passive"))
    (pad "2" smd roundrect (at 0.625 0) (size 0.55 1) (layers "F.Cu" "F.Paste" "F.Mask") (roundrect_rratio 0.15)
      (net 184 "/HDMI converter/LT9611_VCC33_IO") (pintype "passive"))
  )
	(footprint "sa800u-baseboard-hw-footprints:L_0603_1608Metric" (layer "F.Cu")
    (tedit 5D5D3F54)
    (at 146.8 121 180)
    (property "Author" "Antmicro")
    (property "IMax" "")
    (property "ISat" "")
    (property "License" "Apache-2.0")
    (property "MPN" "BRC1608TR35M")
    (property "Manufacturer" "Taiyo Yuden")
    (property "Sheetfile" "hdmi-converter.kicad_sch")
    (property "Sheetname" "HDMI converter")
    (property "Size" "")
    (property "Val" "350n/1.4A")
    (attr smd)
    (fp_text reference "L2" (at -1.1 -0.47 180) (layer "F.SilkS")
      (effects (font (size 0.7 0.7) (thickness 0.15)) (justify left bottom))
    )
    (fp_text value "L_350n_1.4A_0603" (at 0 2 180) (layer "F.Fab")
      (effects (font (size 0.7 0.7) (thickness 0.15)) (justify left bottom))
    )
    (fp_text user "License: Apache-2.0" (at -1.9 5.75 180) (layer "F.Fab") hide
      (effects (font (size 0.7 0.7) (thickness 0.15)) (justify left bottom))
    )
    (fp_text user "${REFERENCE}" (at -1.9 3.1 180) (layer "F.Fab") hide
      (effects (font (size 0.7 0.7) (thickness 0.15)) (justify left bottom))
    )
    (fp_text user "Author: Antmicro" (at -1.9 4.4 180) (layer "F.Fab") hide
      (effects (font (size 0.7 0.7) (thickness 0.15)) (justify left bottom))
    )
    (fp_line (start -0.25 -0.45) (end 0.25 -0.45) (layer "F.SilkS") (width 0.1))
    (fp_line (start -0.25 0.45) (end 0.25 0.45) (layer "F.SilkS") (width 0.1))
    (fp_rect (start -1.15 -0.75) (end 1.15 0.75) (layer "F.CrtYd") (width 0.05) (fill none))
    (fp_rect (start -0.8 -0.4) (end 0.8 0.4) (layer "F.Fab") (width 0.1) (fill none))
    (pad "1" smd roundrect (at -0.625 0 180) (size 0.55 1) (layers "F.Cu" "F.Paste" "F.Mask") (roundrect_rratio 0.15)
      (net 131 "3V3_SYS") (pintype "passive"))
    (pad "2" smd roundrect (at 0.625 0 180) (size 0.55 1) (layers "F.Cu" "F.Paste" "F.Mask") (roundrect_rratio 0.15)
      (net 185 "/HDMI converter/LT9611_VCC33_RX") (pintype "passive"))
  )
)
